(kicad_pcb
	(version 20260206)
	(generator "pcbnew")
	(generator_version "10.0")
	(general
		(thickness 1.6)
		(legacy_teardrops no)
	)
	(paper "A4")
	(title_block
		(title "04192023_DAF0TMB3IC0_F0TG_MB_C_brd_V02_OCP.brd")
		(comment 1 "Grand Teton / footprint 4555 of 8354 (J99), pads 114-226 of 291")
	)
	(layers
		(0 "F.Cu" signal "TOP")
		(4 "In1.Cu" signal "GND")
		(6 "In2.Cu" signal "IN1")
		(8 "In3.Cu" signal "GND1")
		(10 "In4.Cu" signal "IN2")
		(12 "In5.Cu" signal "GND2")
		(14 "In6.Cu" signal "IN3")
		(16 "In7.Cu" signal "GND3")
		(18 "In8.Cu" signal "VCC")
		(20 "In9.Cu" signal "VCC1")
		(22 "In10.Cu" signal "GND4")
		(24 "In11.Cu" signal "IN4")
		(26 "In12.Cu" signal "GND5")
		(28 "In13.Cu" signal "IN5")
		(30 "In14.Cu" signal "GND6")
		(32 "In15.Cu" signal "IN6")
		(34 "In16.Cu" signal "GND7")
		(2 "B.Cu" signal "BOTTOM")
		(9 "F.Adhes" user "F.Adhesive")
		(11 "B.Adhes" user "B.Adhesive")
		(13 "F.Paste" user "Package Geometry/Pastemask Top")
		(15 "B.Paste" user "Package Geometry/Pastemask Bottom")
		(5 "F.SilkS" user "Ref Des/Silkscreen Top")
		(7 "B.SilkS" user "Ref Des/Silkscreen Bottom")
		(1 "F.Mask" user "Board Geometry/Soldermask Top")
		(3 "B.Mask" user "Board Geometry/Soldermask Bottom")
		(17 "Dwgs.User" user "User.Drawings")
		(19 "Cmts.User" user "User.Comments")
		(21 "Eco1.User" user "User.Eco1")
		(23 "Eco2.User" user "User.Eco2")
		(25 "Edge.Cuts" user "Board Geometry/Outline")
		(27 "Margin" user)
		(31 "F.CrtYd" user "Package Geometry/Place Bound Top")
		(29 "B.CrtYd" user "Package Geometry/Place Bound Bottom")
		(35 "F.Fab" user "Ref Des/Assembly Top")
		(33 "B.Fab" user "Ref Des/Assembly Bottom")
	)
	(footprint ""
		(layer "F.Cu")
		(at 196.654166 -255.560322 180)
		(property "Reference" "J99"
			(at -0.4318 -81.730088 0)
			(unlocked yes)
			(layer "F.SilkS")
			(effects
				(font
					(size 0.7874 0.5842)
					(thickness 0.1524)
				)
			)
		)
		(property "Value" ""
			(at 0 0 180)
			(layer "F.Fab")
			(effects
				(font
					(size 1.27 1.27)
				)
			)
		)
		(duplicate_pad_numbers_are_jumpers no)
		(pad "114" smd rect
			(at -2.050034 37.824918 90)
			(size 0.519938 1.4986)
			(layers "F.Cu" "F.Mask" "F.Paste")
			(net "GND")
		)
		(pad "115" smd rect
			(at -2.050034 38.675056 90)
			(size 0.519938 1.4986)
			(layers "F.Cu" "F.Mask" "F.Paste")
			(net "M_K_CPU1_SB_DQS_DP<1>")
		)
		(pad "116" smd rect
			(at -2.050034 39.52494 90)
			(size 0.519938 1.4986)
			(layers "F.Cu" "F.Mask" "F.Paste")
			(net "M_K_CPU1_SB_DQS_DN<1>")
		)
		(pad "117" smd rect
			(at -2.050034 40.375078 90)
			(size 0.519938 1.4986)
			(layers "F.Cu" "F.Mask" "F.Paste")
			(net "GND")
		)
		(pad "118" smd rect
			(at -2.050034 41.224962 90)
			(size 0.519938 1.4986)
			(layers "F.Cu" "F.Mask" "F.Paste")
			(net "M_K_CPU1_SB_DQ<12>")
		)
		(pad "119" smd rect
			(at -2.050034 42.0751 90)
			(size 0.519938 1.4986)
			(layers "F.Cu" "F.Mask" "F.Paste")
			(net "GND")
		)
		(pad "120" smd rect
			(at -2.050034 42.924984 90)
			(size 0.519938 1.4986)
			(layers "F.Cu" "F.Mask" "F.Paste")
			(net "M_K_CPU1_SB_DQ<13>")
		)
		(pad "121" smd rect
			(at -2.050034 43.775122 90)
			(size 0.519938 1.4986)
			(layers "F.Cu" "F.Mask" "F.Paste")
			(net "GND")
		)
		(pad "122" smd rect
			(at -2.050034 44.625006 90)
			(size 0.519938 1.4986)
			(layers "F.Cu" "F.Mask" "F.Paste")
			(net "M_K_CPU1_SB_DQ<16>")
		)
		(pad "123" smd rect
			(at -2.050034 45.47489 90)
			(size 0.519938 1.4986)
			(layers "F.Cu" "F.Mask" "F.Paste")
			(net "GND")
		)
		(pad "124" smd rect
			(at -2.050034 46.325028 90)
			(size 0.519938 1.4986)
			(layers "F.Cu" "F.Mask" "F.Paste")
			(net "M_K_CPU1_SB_DQ<17>")
		)
		(pad "125" smd rect
			(at -2.050034 47.174912 90)
			(size 0.519938 1.4986)
			(layers "F.Cu" "F.Mask" "F.Paste")
			(net "GND")
		)
		(pad "126" smd rect
			(at -2.050034 48.02505 90)
			(size 0.519938 1.4986)
			(layers "F.Cu" "F.Mask" "F.Paste")
			(net "M_K_CPU1_SB_DQS_DP<2>")
		)
		(pad "127" smd rect
			(at -2.050034 48.874934 90)
			(size 0.519938 1.4986)
			(layers "F.Cu" "F.Mask" "F.Paste")
			(net "M_K_CPU1_SB_DQS_DN<2>")
		)
		(pad "128" smd rect
			(at -2.050034 49.725072 90)
			(size 0.519938 1.4986)
			(layers "F.Cu" "F.Mask" "F.Paste")
			(net "GND")
		)
		(pad "129" smd rect
			(at -2.050034 50.574956 90)
			(size 0.519938 1.4986)
			(layers "F.Cu" "F.Mask" "F.Paste")
			(net "M_K_CPU1_SB_DQ<20>")
		)
		(pad "130" smd rect
			(at -2.050034 51.425094 90)
			(size 0.519938 1.4986)
			(layers "F.Cu" "F.Mask" "F.Paste")
			(net "GND")
		)
		(pad "131" smd rect
			(at -2.050034 52.274978 90)
			(size 0.519938 1.4986)
			(layers "F.Cu" "F.Mask" "F.Paste")
			(net "M_K_CPU1_SB_DQ<21>")
		)
		(pad "132" smd rect
			(at -2.050034 53.125116 90)
			(size 0.519938 1.4986)
			(layers "F.Cu" "F.Mask" "F.Paste")
			(net "GND")
		)
		(pad "133" smd rect
			(at -2.050034 53.975 90)
			(size 0.519938 1.4986)
			(layers "F.Cu" "F.Mask" "F.Paste")
			(net "M_K_CPU1_SB_DQ<24>")
		)
		(pad "134" smd rect
			(at -2.050034 54.824884 90)
			(size 0.519938 1.4986)
			(layers "F.Cu" "F.Mask" "F.Paste")
			(net "GND")
		)
		(pad "135" smd rect
			(at -2.050034 55.675022 90)
			(size 0.519938 1.4986)
			(layers "F.Cu" "F.Mask" "F.Paste")
			(net "M_K_CPU1_SB_DQ<25>")
		)
		(pad "136" smd rect
			(at -2.050034 56.524906 90)
			(size 0.519938 1.4986)
			(layers "F.Cu" "F.Mask" "F.Paste")
			(net "GND")
		)
		(pad "137" smd rect
			(at -2.050034 57.375044 90)
			(size 0.519938 1.4986)
			(layers "F.Cu" "F.Mask" "F.Paste")
			(net "M_K_CPU1_SB_DQS_DP<3>")
		)
		(pad "138" smd rect
			(at -2.050034 58.224928 90)
			(size 0.519938 1.4986)
			(layers "F.Cu" "F.Mask" "F.Paste")
			(net "M_K_CPU1_SB_DQS_DN<3>")
		)
		(pad "139" smd rect
			(at -2.050034 59.075066 90)
			(size 0.519938 1.4986)
			(layers "F.Cu" "F.Mask" "F.Paste")
			(net "GND")
		)
		(pad "140" smd rect
			(at -2.050034 59.92495 90)
			(size 0.519938 1.4986)
			(layers "F.Cu" "F.Mask" "F.Paste")
			(net "M_K_CPU1_SB_DQ<28>")
		)
		(pad "141" smd rect
			(at -2.050034 60.775088 90)
			(size 0.519938 1.4986)
			(layers "F.Cu" "F.Mask" "F.Paste")
			(net "GND")
		)
		(pad "142" smd rect
			(at -2.050034 61.624972 90)
			(size 0.519938 1.4986)
			(layers "F.Cu" "F.Mask" "F.Paste")
			(net "M_K_CPU1_SB_DQ<29>")
		)
		(pad "143" smd rect
			(at -2.050034 62.47511 90)
			(size 0.519938 1.4986)
			(layers "F.Cu" "F.Mask" "F.Paste")
			(net "GND")
		)
		(pad "144" smd rect
			(at -2.050034 63.324994 90)
			(size 0.519938 1.4986)
			(layers "F.Cu" "F.Mask" "F.Paste")
			(net "Net_2397")
		)
		(pad "145" smd rect
			(at 2.050034 -63.324994 90)
			(size 0.519938 1.4986)
			(layers "F.Cu" "F.Mask" "F.Paste")
			(net "P12V_MEM_CPU1")
		)
		(pad "146" smd rect
			(at 2.050034 -62.47511 90)
			(size 0.519938 1.4986)
			(layers "F.Cu" "F.Mask" "F.Paste")
			(net "P12V_MEM_CPU1")
		)
		(pad "147" smd rect
			(at 2.050034 -61.624972 90)
			(size 0.519938 1.4986)
			(layers "F.Cu" "F.Mask" "F.Paste")
			(net "PWRGD_CHK_CPU1_DIMM")
		)
		(pad "148" smd rect
			(at 2.050034 -60.775088 90)
			(size 0.519938 1.4986)
			(layers "F.Cu" "F.Mask" "F.Paste")
			(net "PD_CHK_CPU1_DIMM_SAA")
		)
		(pad "149" smd rect
			(at 2.050034 -59.92495 90)
			(size 0.519938 1.4986)
			(layers "F.Cu" "F.Mask" "F.Paste")
			(net "Net_2398")
		)
		(pad "150" smd rect
			(at 2.050034 -59.075066 90)
			(size 0.519938 1.4986)
			(layers "F.Cu" "F.Mask" "F.Paste")
			(net "Net_2399")
		)
		(pad "151" smd rect
			(at 2.050034 -58.224928 90)
			(size 0.519938 1.4986)
			(layers "F.Cu" "F.Mask" "F.Paste")
			(net "GND")
		)
		(pad "152" smd rect
			(at 2.050034 -57.375044 90)
			(size 0.519938 1.4986)
			(layers "F.Cu" "F.Mask" "F.Paste")
			(net "M_K_CPU1_SA_DQ<2>")
		)
		(pad "153" smd rect
			(at 2.050034 -56.524906 90)
			(size 0.519938 1.4986)
			(layers "F.Cu" "F.Mask" "F.Paste")
			(net "GND")
		)
		(pad "154" smd rect
			(at 2.050034 -55.675022 90)
			(size 0.519938 1.4986)
			(layers "F.Cu" "F.Mask" "F.Paste")
			(net "M_K_CPU1_SA_DQ<3>")
		)
		(pad "155" smd rect
			(at 2.050034 -54.824884 90)
			(size 0.519938 1.4986)
			(layers "F.Cu" "F.Mask" "F.Paste")
			(net "GND")
		)
		(pad "156" smd rect
			(at 2.050034 -53.975 90)
			(size 0.519938 1.4986)
			(layers "F.Cu" "F.Mask" "F.Paste")
			(net "M_K_CPU1_SA_DQS_DN<5>")
		)
		(pad "157" smd rect
			(at 2.050034 -53.125116 90)
			(size 0.519938 1.4986)
			(layers "F.Cu" "F.Mask" "F.Paste")
			(net "M_K_CPU1_SA_DQS_DP<5>")
		)
		(pad "158" smd rect
			(at 2.050034 -52.274978 90)
			(size 0.519938 1.4986)
			(layers "F.Cu" "F.Mask" "F.Paste")
			(net "GND")
		)
		(pad "159" smd rect
			(at 2.050034 -51.425094 90)
			(size 0.519938 1.4986)
			(layers "F.Cu" "F.Mask" "F.Paste")
			(net "M_K_CPU1_SA_DQ<6>")
		)
		(pad "160" smd rect
			(at 2.050034 -50.574956 90)
			(size 0.519938 1.4986)
			(layers "F.Cu" "F.Mask" "F.Paste")
			(net "GND")
		)
		(pad "161" smd rect
			(at 2.050034 -49.725072 90)
			(size 0.519938 1.4986)
			(layers "F.Cu" "F.Mask" "F.Paste")
			(net "M_K_CPU1_SA_DQ<7>")
		)
		(pad "162" smd rect
			(at 2.050034 -48.874934 90)
			(size 0.519938 1.4986)
			(layers "F.Cu" "F.Mask" "F.Paste")
			(net "GND")
		)
		(pad "163" smd rect
			(at 2.050034 -48.02505 90)
			(size 0.519938 1.4986)
			(layers "F.Cu" "F.Mask" "F.Paste")
			(net "M_K_CPU1_SA_DQ<10>")
		)
		(pad "164" smd rect
			(at 2.050034 -47.174912 90)
			(size 0.519938 1.4986)
			(layers "F.Cu" "F.Mask" "F.Paste")
			(net "GND")
		)
		(pad "165" smd rect
			(at 2.050034 -46.325028 90)
			(size 0.519938 1.4986)
			(layers "F.Cu" "F.Mask" "F.Paste")
			(net "M_K_CPU1_SA_DQ<11>")
		)
		(pad "166" smd rect
			(at 2.050034 -45.47489 90)
			(size 0.519938 1.4986)
			(layers "F.Cu" "F.Mask" "F.Paste")
			(net "GND")
		)
		(pad "167" smd rect
			(at 2.050034 -44.625006 90)
			(size 0.519938 1.4986)
			(layers "F.Cu" "F.Mask" "F.Paste")
			(net "M_K_CPU1_SA_DQS_DN<6>")
		)
		(pad "168" smd rect
			(at 2.050034 -43.775122 90)
			(size 0.519938 1.4986)
			(layers "F.Cu" "F.Mask" "F.Paste")
			(net "M_K_CPU1_SA_DQS_DP<6>")
		)
		(pad "169" smd rect
			(at 2.050034 -42.924984 90)
			(size 0.519938 1.4986)
			(layers "F.Cu" "F.Mask" "F.Paste")
			(net "GND")
		)
		(pad "170" smd rect
			(at 2.050034 -42.0751 90)
			(size 0.519938 1.4986)
			(layers "F.Cu" "F.Mask" "F.Paste")
			(net "M_K_CPU1_SA_DQ<14>")
		)
		(pad "171" smd rect
			(at 2.050034 -41.224962 90)
			(size 0.519938 1.4986)
			(layers "F.Cu" "F.Mask" "F.Paste")
			(net "GND")
		)
		(pad "172" smd rect
			(at 2.050034 -40.375078 90)
			(size 0.519938 1.4986)
			(layers "F.Cu" "F.Mask" "F.Paste")
			(net "M_K_CPU1_SA_DQ<15>")
		)
		(pad "173" smd rect
			(at 2.050034 -39.52494 90)
			(size 0.519938 1.4986)
			(layers "F.Cu" "F.Mask" "F.Paste")
			(net "GND")
		)
		(pad "174" smd rect
			(at 2.050034 -38.675056 90)
			(size 0.519938 1.4986)
			(layers "F.Cu" "F.Mask" "F.Paste")
			(net "M_K_CPU1_SA_DQ<18>")
		)
		(pad "175" smd rect
			(at 2.050034 -37.824918 90)
			(size 0.519938 1.4986)
			(layers "F.Cu" "F.Mask" "F.Paste")
			(net "GND")
		)
		(pad "176" smd rect
			(at 2.050034 -36.975034 90)
			(size 0.519938 1.4986)
			(layers "F.Cu" "F.Mask" "F.Paste")
			(net "M_K_CPU1_SA_DQ<19>")
		)
		(pad "177" smd rect
			(at 2.050034 -36.124896 90)
			(size 0.519938 1.4986)
			(layers "F.Cu" "F.Mask" "F.Paste")
			(net "GND")
		)
		(pad "178" smd rect
			(at 2.050034 -35.275012 90)
			(size 0.519938 1.4986)
			(layers "F.Cu" "F.Mask" "F.Paste")
			(net "M_K_CPU1_SA_DQS_DN<7>")
		)
		(pad "179" smd rect
			(at 2.050034 -34.425128 90)
			(size 0.519938 1.4986)
			(layers "F.Cu" "F.Mask" "F.Paste")
			(net "M_K_CPU1_SA_DQS_DP<7>")
		)
		(pad "180" smd rect
			(at 2.050034 -33.57499 90)
			(size 0.519938 1.4986)
			(layers "F.Cu" "F.Mask" "F.Paste")
			(net "GND")
		)
		(pad "181" smd rect
			(at 2.050034 -32.725106 90)
			(size 0.519938 1.4986)
			(layers "F.Cu" "F.Mask" "F.Paste")
			(net "M_K_CPU1_SA_DQ<22>")
		)
		(pad "182" smd rect
			(at 2.050034 -31.874968 90)
			(size 0.519938 1.4986)
			(layers "F.Cu" "F.Mask" "F.Paste")
			(net "GND")
		)
		(pad "183" smd rect
			(at 2.050034 -31.025084 90)
			(size 0.519938 1.4986)
			(layers "F.Cu" "F.Mask" "F.Paste")
			(net "M_K_CPU1_SA_DQ<23>")
		)
		(pad "184" smd rect
			(at 2.050034 -30.174946 90)
			(size 0.519938 1.4986)
			(layers "F.Cu" "F.Mask" "F.Paste")
			(net "GND")
		)
		(pad "185" smd rect
			(at 2.050034 -29.325062 90)
			(size 0.519938 1.4986)
			(layers "F.Cu" "F.Mask" "F.Paste")
			(net "M_K_CPU1_SA_DQ<26>")
		)
		(pad "186" smd rect
			(at 2.050034 -28.474924 90)
			(size 0.519938 1.4986)
			(layers "F.Cu" "F.Mask" "F.Paste")
			(net "GND")
		)
		(pad "187" smd rect
			(at 2.050034 -27.62504 90)
			(size 0.519938 1.4986)
			(layers "F.Cu" "F.Mask" "F.Paste")
			(net "M_K_CPU1_SA_DQ<27>")
		)
		(pad "188" smd rect
			(at 2.050034 -26.774902 90)
			(size 0.519938 1.4986)
			(layers "F.Cu" "F.Mask" "F.Paste")
			(net "GND")
		)
		(pad "189" smd rect
			(at 2.050034 -25.925018 90)
			(size 0.519938 1.4986)
			(layers "F.Cu" "F.Mask" "F.Paste")
			(net "M_K_CPU1_SA_DQS_DN<8>")
		)
		(pad "190" smd rect
			(at 2.050034 -25.07488 90)
			(size 0.519938 1.4986)
			(layers "F.Cu" "F.Mask" "F.Paste")
			(net "M_K_CPU1_SA_DQS_DP<8>")
		)
		(pad "191" smd rect
			(at 2.050034 -24.224996 90)
			(size 0.519938 1.4986)
			(layers "F.Cu" "F.Mask" "F.Paste")
			(net "GND")
		)
		(pad "192" smd rect
			(at 2.050034 -23.375112 90)
			(size 0.519938 1.4986)
			(layers "F.Cu" "F.Mask" "F.Paste")
			(net "M_K_CPU1_SA_DQ<30>")
		)
		(pad "193" smd rect
			(at 2.050034 -22.524974 90)
			(size 0.519938 1.4986)
			(layers "F.Cu" "F.Mask" "F.Paste")
			(net "GND")
		)
		(pad "194" smd rect
			(at 2.050034 -21.67509 90)
			(size 0.519938 1.4986)
			(layers "F.Cu" "F.Mask" "F.Paste")
			(net "M_K_CPU1_SA_DQ<31>")
		)
		(pad "195" smd rect
			(at 2.050034 -20.824952 90)
			(size 0.519938 1.4986)
			(layers "F.Cu" "F.Mask" "F.Paste")
			(net "GND")
		)
		(pad "196" smd rect
			(at 2.050034 -19.975068 90)
			(size 0.519938 1.4986)
			(layers "F.Cu" "F.Mask" "F.Paste")
			(net "M_K_CPU1_SA_CB<2>")
		)
		(pad "197" smd rect
			(at 2.050034 -19.12493 90)
			(size 0.519938 1.4986)
			(layers "F.Cu" "F.Mask" "F.Paste")
			(net "GND")
		)
		(pad "198" smd rect
			(at 2.050034 -18.275046 90)
			(size 0.519938 1.4986)
			(layers "F.Cu" "F.Mask" "F.Paste")
			(net "M_K_CPU1_SA_CB<3>")
		)
		(pad "199" smd rect
			(at 2.050034 -17.424908 90)
			(size 0.519938 1.4986)
			(layers "F.Cu" "F.Mask" "F.Paste")
			(net "GND")
		)
		(pad "200" smd rect
			(at 2.050034 -16.575024 90)
			(size 0.519938 1.4986)
			(layers "F.Cu" "F.Mask" "F.Paste")
			(net "M_K_CPU1_SA_DQS_DN<9>")
		)
		(pad "201" smd rect
			(at 2.050034 -15.724886 90)
			(size 0.519938 1.4986)
			(layers "F.Cu" "F.Mask" "F.Paste")
			(net "M_K_CPU1_SA_DQS_DP<9>")
		)
		(pad "202" smd rect
			(at 2.050034 -14.875002 90)
			(size 0.519938 1.4986)
			(layers "F.Cu" "F.Mask" "F.Paste")
			(net "GND")
		)
		(pad "203" smd rect
			(at 2.050034 -14.025118 90)
			(size 0.519938 1.4986)
			(layers "F.Cu" "F.Mask" "F.Paste")
			(net "M_K_CPU1_SA_CB<6>")
		)
		(pad "204" smd rect
			(at 2.050034 -13.17498 90)
			(size 0.519938 1.4986)
			(layers "F.Cu" "F.Mask" "F.Paste")
			(net "GND")
		)
		(pad "205" smd rect
			(at 2.050034 -12.325096 90)
			(size 0.519938 1.4986)
			(layers "F.Cu" "F.Mask" "F.Paste")
			(net "M_K_CPU1_SA_CB<7>")
		)
		(pad "206" smd rect
			(at 2.050034 -11.474958 90)
			(size 0.519938 1.4986)
			(layers "F.Cu" "F.Mask" "F.Paste")
			(net "GND")
		)
		(pad "207" smd rect
			(at 2.050034 -10.625074 90)
			(size 0.519938 1.4986)
			(layers "F.Cu" "F.Mask" "F.Paste")
			(net "M_K_CPU1_RESET_N")
		)
		(pad "208" smd rect
			(at 2.050034 -9.774936 90)
			(size 0.519938 1.4986)
			(layers "F.Cu" "F.Mask" "F.Paste")
			(net "GND")
		)
		(pad "209" smd rect
			(at 2.050034 -8.925052 90)
			(size 0.519938 1.4986)
			(layers "F.Cu" "F.Mask" "F.Paste")
			(net "M_K_CPU1_SA_CS_N<1>")
		)
		(pad "210" smd rect
			(at 2.050034 -8.074914 90)
			(size 0.519938 1.4986)
			(layers "F.Cu" "F.Mask" "F.Paste")
			(net "GND")
		)
		(pad "211" smd rect
			(at 2.050034 -7.22503 90)
			(size 0.519938 1.4986)
			(layers "F.Cu" "F.Mask" "F.Paste")
			(net "M_K_CPU1_SA_CA<1>")
		)
		(pad "212" smd rect
			(at 2.050034 -6.374892 90)
			(size 0.519938 1.4986)
			(layers "F.Cu" "F.Mask" "F.Paste")
			(net "GND")
		)
		(pad "213" smd rect
			(at 2.050034 -5.525008 90)
			(size 0.519938 1.4986)
			(layers "F.Cu" "F.Mask" "F.Paste")
			(net "M_K_CPU1_SA_CA<3>")
		)
		(pad "214" smd rect
			(at 2.050034 -4.675124 90)
			(size 0.519938 1.4986)
			(layers "F.Cu" "F.Mask" "F.Paste")
			(net "GND")
		)
		(pad "215" smd rect
			(at 2.050034 -3.824986 90)
			(size 0.519938 1.4986)
			(layers "F.Cu" "F.Mask" "F.Paste")
			(net "M_K_CPU1_SA_CA<5>")
		)
		(pad "216" smd rect
			(at 2.050034 -2.975102 90)
			(size 0.519938 1.4986)
			(layers "F.Cu" "F.Mask" "F.Paste")
			(net "GND")
		)
		(pad "217" smd rect
			(at 2.050034 -2.124964 90)
			(size 0.519938 1.4986)
			(layers "F.Cu" "F.Mask" "F.Paste")
			(net "M_K_CPU1_CLK_DP<0>")
		)
		(pad "218" smd rect
			(at 2.050034 -1.27508 90)
			(size 0.519938 1.4986)
			(layers "F.Cu" "F.Mask" "F.Paste")
			(net "M_K_CPU1_CLK_DN<0>")
		)
		(pad "219" smd rect
			(at 2.050034 -0.424942 90)
			(size 0.519938 1.4986)
			(layers "F.Cu" "F.Mask" "F.Paste")
			(net "GND")
		)
		(pad "220" smd rect
			(at 2.050034 5.525008 90)
			(size 0.519938 1.4986)
			(layers "F.Cu" "F.Mask" "F.Paste")
			(net "Net_2400")
		)
		(pad "221" smd rect
			(at 2.050034 6.374892 90)
			(size 0.519938 1.4986)
			(layers "F.Cu" "F.Mask" "F.Paste")
			(net "M_K_CPU1_SB_CA<1>")
		)
		(pad "222" smd rect
			(at 2.050034 7.22503 90)
			(size 0.519938 1.4986)
			(layers "F.Cu" "F.Mask" "F.Paste")
			(net "GND")
		)
		(pad "223" smd rect
			(at 2.050034 8.074914 90)
			(size 0.519938 1.4986)
			(layers "F.Cu" "F.Mask" "F.Paste")
			(net "M_K_CPU1_SB_CA<3>")
		)
		(pad "224" smd rect
			(at 2.050034 8.925052 90)
			(size 0.519938 1.4986)
			(layers "F.Cu" "F.Mask" "F.Paste")
			(net "GND")
		)
		(pad "225" smd rect
			(at 2.050034 9.774936 90)
			(size 0.519938 1.4986)
			(layers "F.Cu" "F.Mask" "F.Paste")
			(net "M_K_CPU1_SB_CA<5>")
		)
		(pad "226" smd rect
			(at 2.050034 10.625074 90)
			(size 0.519938 1.4986)
			(layers "F.Cu" "F.Mask" "F.Paste")
			(net "GND")
		)
	)
)
